# T6G (Grand Teton) — schematic netlist excerpt (pin names and nets, part order shuffled) for the footprints in the layout excerpt that follows; sources: Cadence DE-HDL packaged netlist, KiCad conversion of 04192023_DAF0TMB3IC0_F0TG_MB_C_brd_V02_OCP.brd

PR49  Q_RES  49.9 1% CHIP  pkg 0402LF  page 200 : A = VSENSE_VSS_SENSE_C_P0 ; B = GND
C304  Q_CAP  10PF 50V 5% EMPTY  pkg 0402  page 200 : A = SVID_PVDDCR_CPU1_P0_SVD_R ; B = GND
C1542  Q_CAP_DIFFBUS  DIFF BUS_0.22UF 6.3V 20% X6S  pkg C0201  page 67 : \1\ = P5E_CPU1_P3_TX_C_DN<2> ; \2\ = P5E_CPU1_P3_TX_DN<2>

(kicad_pcb
	(version 20260206)
	(generator "pcbnew")
	(generator_version "10.0")
	(general
		(thickness 1.6)
		(legacy_teardrops no)
	)
	(paper "A4")
	(title_block
		(title "04192023_DAF0TMB3IC0_F0TG_MB_C_brd_V02_OCP.brd")
		(comment 1 "Grand Teton / footprints 4540-4542 of 8354")
	)
	(layers
		(0 "F.Cu" signal "TOP")
		(4 "In1.Cu" signal "GND")
		(6 "In2.Cu" signal "IN1")
		(8 "In3.Cu" signal "GND1")
		(10 "In4.Cu" signal "IN2")
		(12 "In5.Cu" signal "GND2")
		(14 "In6.Cu" signal "IN3")
		(16 "In7.Cu" signal "GND3")
		(18 "In8.Cu" signal "VCC")
		(20 "In9.Cu" signal "VCC1")
		(22 "In10.Cu" signal "GND4")
		(24 "In11.Cu" signal "IN4")
		(26 "In12.Cu" signal "GND5")
		(28 "In13.Cu" signal "IN5")
		(30 "In14.Cu" signal "GND6")
		(32 "In15.Cu" signal "IN6")
		(34 "In16.Cu" signal "GND7")
		(2 "B.Cu" signal "BOTTOM")
		(9 "F.Adhes" user "F.Adhesive")
		(11 "B.Adhes" user "B.Adhesive")
		(13 "F.Paste" user "Package Geometry/Pastemask Top")
		(15 "B.Paste" user "Package Geometry/Pastemask Bottom")
		(5 "F.SilkS" user "Ref Des/Silkscreen Top")
		(7 "B.SilkS" user "Ref Des/Silkscreen Bottom")
		(1 "F.Mask" user "Board Geometry/Soldermask Top")
		(3 "B.Mask" user "Board Geometry/Soldermask Bottom")
		(17 "Dwgs.User" user "User.Drawings")
		(19 "Cmts.User" user "User.Comments")
		(21 "Eco1.User" user "User.Eco1")
		(23 "Eco2.User" user "User.Eco2")
		(25 "Edge.Cuts" user "Board Geometry/Outline")
		(27 "Margin" user)
		(31 "F.CrtYd" user "Package Geometry/Place Bound Top")
		(29 "B.CrtYd" user "Package Geometry/Place Bound Bottom")
		(35 "F.Fab" user "Ref Des/Assembly Top")
		(33 "B.Fab" user "Ref Des/Assembly Bottom")
	)
	(footprint ""
		(layer "F.Cu")
		(at 357.93426 -326.58431 180)
		(property "Reference" "PR49"
			(at 0 0 180)
			(layer "F.SilkS")
			(hide yes)
			(effects
				(font
					(size 1.27 1.27)
				)
			)
		)
		(property "Value" ""
			(at 0 0 180)
			(layer "F.Fab")
			(effects
				(font
					(size 1.27 1.27)
				)
			)
		)
		(duplicate_pad_numbers_are_jumpers no)
		(fp_line
			(start 0.7874 0.4064)
			(end -0.7874 0.4064)
			(stroke
				(width 0.1524)
				(type default)
			)
			(layer "F.SilkS")
		)
		(fp_line
			(start 0.7874 -0.4064)
			(end 0.7874 0.4064)
			(stroke
				(width 0.1524)
				(type default)
			)
			(layer "F.SilkS")
		)
		(fp_line
			(start -0.7874 0.4064)
			(end -0.7874 -0.4064)
			(stroke
				(width 0.1524)
				(type default)
			)
			(layer "F.SilkS")
		)
		(fp_line
			(start -0.7874 -0.4064)
			(end 0.7874 -0.4064)
			(stroke
				(width 0.1524)
				(type default)
			)
			(layer "F.SilkS")
		)
		(fp_line
			(start 0.67945 0.3048)
			(end 0.120396 0.3048)
			(stroke
				(width 0.1)
				(type default)
			)
			(layer "F.Fab")
		)
		(fp_line
			(start 0.67945 -0.3048)
			(end 0.67945 0.3048)
			(stroke
				(width 0.1)
				(type default)
			)
			(layer "F.Fab")
		)
		(fp_line
			(start 0.12065 -0.2794)
			(end 0.12065 -0.3048)
			(stroke
				(width 0.1)
				(type default)
			)
			(layer "F.Fab")
		)
		(fp_line
			(start 0.12065 -0.3048)
			(end 0.67945 -0.3048)
			(stroke
				(width 0.1)
				(type default)
			)
			(layer "F.Fab")
		)
		(fp_line
			(start 0.120396 0.3048)
			(end 0.120396 0.2794)
			(stroke
				(width 0.1)
				(type default)
			)
			(layer "F.Fab")
		)
		(fp_line
			(start 0.120396 0.2794)
			(end -0.12065 0.2794)
			(stroke
				(width 0.1)
				(type default)
			)
			(layer "F.Fab")
		)
		(fp_line
			(start -0.12065 0.3048)
			(end -0.67945 0.3048)
			(stroke
				(width 0.1)
				(type default)
			)
			(layer "F.Fab")
		)
		(fp_line
			(start -0.12065 0.2794)
			(end -0.12065 0.3048)
			(stroke
				(width 0.1)
				(type default)
			)
			(layer "F.Fab")
		)
		(fp_line
			(start -0.12065 -0.2794)
			(end 0.12065 -0.2794)
			(stroke
				(width 0.1)
				(type default)
			)
			(layer "F.Fab")
		)
		(fp_line
			(start -0.12065 -0.305054)
			(end -0.12065 -0.2794)
			(stroke
				(width 0.1)
				(type default)
			)
			(layer "F.Fab")
		)
		(fp_line
			(start -0.67945 0.3048)
			(end -0.67945 -0.305054)
			(stroke
				(width 0.1)
				(type default)
			)
			(layer "F.Fab")
		)
		(fp_line
			(start -0.67945 -0.305054)
			(end -0.12065 -0.305054)
			(stroke
				(width 0.1)
				(type default)
			)
			(layer "F.Fab")
		)
		(pad "1" smd circle
			(at -0.40005 0 180)
			(size 0 0)
			(layers "F.Cu" "F.Mask" "F.Paste")
			(net "VSENSE_VSS_SENSE_C_P0")
		)
		(pad "2" smd circle
			(at 0.40005 0 180)
			(size 0 0)
			(layers "F.Cu" "F.Mask" "F.Paste")
			(net "GND")
		)
	)
	(footprint ""
		(layer "F.Cu")
		(at 302.133 -358.14 180)
		(property "Reference" "C304"
			(at 0 0 180)
			(layer "F.SilkS")
			(hide yes)
			(effects
				(font
					(size 1.27 1.27)
				)
			)
		)
		(property "Value" ""
			(at 0 0 180)
			(layer "F.Fab")
			(effects
				(font
					(size 1.27 1.27)
				)
			)
		)
		(duplicate_pad_numbers_are_jumpers no)
		(fp_line
			(start 0.7874 0.4064)
			(end -0.7874 0.4064)
			(stroke
				(width 0.1524)
				(type default)
			)
			(layer "F.SilkS")
		)
		(fp_line
			(start 0.7874 -0.4064)
			(end 0.7874 0.4064)
			(stroke
				(width 0.1524)
				(type default)
			)
			(layer "F.SilkS")
		)
		(fp_line
			(start -0.7874 0.4064)
			(end -0.7874 -0.4064)
			(stroke
				(width 0.1524)
				(type default)
			)
			(layer "F.SilkS")
		)
		(fp_line
			(start -0.7874 -0.4064)
			(end 0.7874 -0.4064)
			(stroke
				(width 0.1524)
				(type default)
			)
			(layer "F.SilkS")
		)
		(fp_line
			(start 0.67945 0.3048)
			(end 0.120396 0.3048)
			(stroke
				(width 0.1)
				(type default)
			)
			(layer "F.Fab")
		)
		(fp_line
			(start 0.67945 -0.3048)
			(end 0.67945 0.3048)
			(stroke
				(width 0.1)
				(type default)
			)
			(layer "F.Fab")
		)
		(fp_line
			(start 0.12065 -0.2794)
			(end 0.12065 -0.3048)
			(stroke
				(width 0.1)
				(type default)
			)
			(layer "F.Fab")
		)
		(fp_line
			(start 0.12065 -0.3048)
			(end 0.67945 -0.3048)
			(stroke
				(width 0.1)
				(type default)
			)
			(layer "F.Fab")
		)
		(fp_line
			(start 0.120396 0.3048)
			(end 0.120396 0.2794)
			(stroke
				(width 0.1)
				(type default)
			)
			(layer "F.Fab")
		)
		(fp_line
			(start 0.120396 0.2794)
			(end -0.12065 0.2794)
			(stroke
				(width 0.1)
				(type default)
			)
			(layer "F.Fab")
		)
		(fp_line
			(start -0.12065 0.3048)
			(end -0.67945 0.3048)
			(stroke
				(width 0.1)
				(type default)
			)
			(layer "F.Fab")
		)
		(fp_line
			(start -0.12065 0.2794)
			(end -0.12065 0.3048)
			(stroke
				(width 0.1)
				(type default)
			)
			(layer "F.Fab")
		)
		(fp_line
			(start -0.12065 -0.2794)
			(end 0.12065 -0.2794)
			(stroke
				(width 0.1)
				(type default)
			)
			(layer "F.Fab")
		)
		(fp_line
			(start -0.12065 -0.305054)
			(end -0.12065 -0.2794)
			(stroke
				(width 0.1)
				(type default)
			)
			(layer "F.Fab")
		)
		(fp_line
			(start -0.67945 0.3048)
			(end -0.67945 -0.305054)
			(stroke
				(width 0.1)
				(type default)
			)
			(layer "F.Fab")
		)
		(fp_line
			(start -0.67945 -0.305054)
			(end -0.12065 -0.305054)
			(stroke
				(width 0.1)
				(type default)
			)
			(layer "F.Fab")
		)
		(pad "1" smd circle
			(at -0.40005 0 180)
			(size 0 0)
			(layers "F.Cu" "F.Mask" "F.Paste")
			(net "SVID_PVDDCR_CPU1_P0_SVD_R")
		)
		(pad "2" smd circle
			(at 0.40005 0 180)
			(size 0 0)
			(layers "F.Cu" "F.Mask" "F.Paste")
			(net "GND")
		)
	)
	(footprint ""
		(layer "F.Cu")
		(at 111.004096 -373.03583 -90)
		(property "Reference" "C1542"
			(at 0 0 270)
			(layer "F.SilkS")
			(hide yes)
			(effects
				(font
					(size 1.27 1.27)
				)
			)
		)
		(property "Value" ""
			(at 0 0 270)
			(layer "F.Fab")
			(effects
				(font
					(size 1.27 1.27)
				)
			)
		)
		(duplicate_pad_numbers_are_jumpers no)
		(fp_line
			(start -0.299974 0.150114)
			(end -0.299974 -0.150114)
			(stroke
				(width 0.1)
				(type default)
			)
			(layer "F.Fab")
		)
		(fp_line
			(start 0.299974 0.150114)
			(end -0.299974 0.150114)
			(stroke
				(width 0.1)
				(type default)
			)
			(layer "F.Fab")
		)
		(fp_line
			(start -0.299974 -0.150114)
			(end 0.299974 -0.150114)
			(stroke
				(width 0.1)
				(type default)
			)
			(layer "F.Fab")
		)
		(fp_line
			(start 0.299974 -0.150114)
			(end 0.299974 0.150114)
			(stroke
				(width 0.1)
				(type default)
			)
			(layer "F.Fab")
		)
		(pad "1" smd rect
			(at -0.2667 0 270)
			(size 0.3048 0.381)
			(layers "F.Cu" "F.Mask" "F.Paste")
			(net "P5E_CPU1_P3_TX_C_DN<2>")
		)
		(pad "2" smd rect
			(at 0.2667 0 270)
			(size 0.3048 0.381)
			(layers "F.Cu" "F.Mask" "F.Paste")
			(net "P5E_CPU1_P3_TX_DN<2>")
		)
	)
)
